# T6G (Grand Teton) — schematic netlist excerpt (pin names and nets, part order shuffled) for the footprints in the layout excerpt that follows; sources: Cadence DE-HDL packaged netlist, KiCad conversion of 04192023_DAF0TMB3IC0_F0TG_MB_C_brd_V02_OCP.brd

R9023  Q_RES  33.2 1% CHIP  pkg 0402LF  page 136 : A = RST_PERST_OCP_SFF_N ; B = RST_PERST_OCP_SFF_R_N
PC151_2  Q_CAP  1UF 25V 10% X6S  pkg C0402  page 205 : A = SW_P12V_AUX_PVDDIO_P0_FLT ; B = GND

(kicad_pcb
	(version 20260206)
	(generator "pcbnew")
	(generator_version "10.0")
	(general
		(thickness 1.6)
		(legacy_teardrops no)
	)
	(paper "A4")
	(title_block
		(title "04192023_DAF0TMB3IC0_F0TG_MB_C_brd_V02_OCP.brd")
		(comment 1 "Grand Teton / footprints 2966-2967 of 8354")
	)
	(layers
		(0 "F.Cu" signal "TOP")
		(4 "In1.Cu" signal "GND")
		(6 "In2.Cu" signal "IN1")
		(8 "In3.Cu" signal "GND1")
		(10 "In4.Cu" signal "IN2")
		(12 "In5.Cu" signal "GND2")
		(14 "In6.Cu" signal "IN3")
		(16 "In7.Cu" signal "GND3")
		(18 "In8.Cu" signal "VCC")
		(20 "In9.Cu" signal "VCC1")
		(22 "In10.Cu" signal "GND4")
		(24 "In11.Cu" signal "IN4")
		(26 "In12.Cu" signal "GND5")
		(28 "In13.Cu" signal "IN5")
		(30 "In14.Cu" signal "GND6")
		(32 "In15.Cu" signal "IN6")
		(34 "In16.Cu" signal "GND7")
		(2 "B.Cu" signal "BOTTOM")
		(9 "F.Adhes" user "F.Adhesive")
		(11 "B.Adhes" user "B.Adhesive")
		(13 "F.Paste" user "Package Geometry/Pastemask Top")
		(15 "B.Paste" user "Package Geometry/Pastemask Bottom")
		(5 "F.SilkS" user "Ref Des/Silkscreen Top")
		(7 "B.SilkS" user "Ref Des/Silkscreen Bottom")
		(1 "F.Mask" user "Board Geometry/Soldermask Top")
		(3 "B.Mask" user "Board Geometry/Soldermask Bottom")
		(17 "Dwgs.User" user "User.Drawings")
		(19 "Cmts.User" user "User.Comments")
		(21 "Eco1.User" user "User.Eco1")
		(23 "Eco2.User" user "User.Eco2")
		(25 "Edge.Cuts" user "Board Geometry/Outline")
		(27 "Margin" user)
		(31 "F.CrtYd" user "Package Geometry/Place Bound Top")
		(29 "B.CrtYd" user "Package Geometry/Place Bound Bottom")
		(35 "F.Fab" user "Ref Des/Assembly Top")
		(33 "B.Fab" user "Ref Des/Assembly Bottom")
	)
	(footprint ""
		(layer "F.Cu")
		(at 211.709 -119.634)
		(property "Reference" "R9023"
			(at 0 0 0)
			(layer "F.SilkS")
			(hide yes)
			(effects
				(font
					(size 1.27 1.27)
				)
			)
		)
		(property "Value" ""
			(at 0 0 0)
			(layer "F.Fab")
			(effects
				(font
					(size 1.27 1.27)
				)
			)
		)
		(duplicate_pad_numbers_are_jumpers no)
		(fp_line
			(start -0.7874 -0.4064)
			(end 0.7874 -0.4064)
			(stroke
				(width 0.1524)
				(type default)
			)
			(layer "F.SilkS")
		)
		(fp_line
			(start -0.7874 0.4064)
			(end -0.7874 -0.4064)
			(stroke
				(width 0.1524)
				(type default)
			)
			(layer "F.SilkS")
		)
		(fp_line
			(start 0.7874 -0.4064)
			(end 0.7874 0.4064)
			(stroke
				(width 0.1524)
				(type default)
			)
			(layer "F.SilkS")
		)
		(fp_line
			(start 0.7874 0.4064)
			(end -0.7874 0.4064)
			(stroke
				(width 0.1524)
				(type default)
			)
			(layer "F.SilkS")
		)
		(fp_line
			(start -0.67945 -0.305054)
			(end -0.12065 -0.305054)
			(stroke
				(width 0.1)
				(type default)
			)
			(layer "F.Fab")
		)
		(fp_line
			(start -0.67945 0.3048)
			(end -0.67945 -0.305054)
			(stroke
				(width 0.1)
				(type default)
			)
			(layer "F.Fab")
		)
		(fp_line
			(start -0.12065 -0.305054)
			(end -0.12065 -0.2794)
			(stroke
				(width 0.1)
				(type default)
			)
			(layer "F.Fab")
		)
		(fp_line
			(start -0.12065 -0.2794)
			(end 0.12065 -0.2794)
			(stroke
				(width 0.1)
				(type default)
			)
			(layer "F.Fab")
		)
		(fp_line
			(start -0.12065 0.2794)
			(end -0.12065 0.3048)
			(stroke
				(width 0.1)
				(type default)
			)
			(layer "F.Fab")
		)
		(fp_line
			(start -0.12065 0.3048)
			(end -0.67945 0.3048)
			(stroke
				(width 0.1)
				(type default)
			)
			(layer "F.Fab")
		)
		(fp_line
			(start 0.120396 0.2794)
			(end -0.12065 0.2794)
			(stroke
				(width 0.1)
				(type default)
			)
			(layer "F.Fab")
		)
		(fp_line
			(start 0.120396 0.3048)
			(end 0.120396 0.2794)
			(stroke
				(width 0.1)
				(type default)
			)
			(layer "F.Fab")
		)
		(fp_line
			(start 0.12065 -0.3048)
			(end 0.67945 -0.3048)
			(stroke
				(width 0.1)
				(type default)
			)
			(layer "F.Fab")
		)
		(fp_line
			(start 0.12065 -0.2794)
			(end 0.12065 -0.3048)
			(stroke
				(width 0.1)
				(type default)
			)
			(layer "F.Fab")
		)
		(fp_line
			(start 0.67945 -0.3048)
			(end 0.67945 0.3048)
			(stroke
				(width 0.1)
				(type default)
			)
			(layer "F.Fab")
		)
		(fp_line
			(start 0.67945 0.3048)
			(end 0.120396 0.3048)
			(stroke
				(width 0.1)
				(type default)
			)
			(layer "F.Fab")
		)
		(pad "1" smd circle
			(at -0.40005 0)
			(size 0 0)
			(layers "F.Cu" "F.Mask" "F.Paste")
			(net "RST_PERST_OCP_SFF_N")
		)
		(pad "2" smd circle
			(at 0.40005 0)
			(size 0 0)
			(layers "F.Cu" "F.Mask" "F.Paste")
			(net "RST_PERST_OCP_SFF_R_N")
		)
	)
	(footprint ""
		(layer "F.Cu")
		(at 295.642792 -346.866464 -90)
		(property "Reference" "PC151_2"
			(at 0 0 270)
			(layer "F.SilkS")
			(hide yes)
			(effects
				(font
					(size 1.27 1.27)
				)
			)
		)
		(property "Value" ""
			(at 0 0 270)
			(layer "F.Fab")
			(effects
				(font
					(size 1.27 1.27)
				)
			)
		)
		(duplicate_pad_numbers_are_jumpers no)
		(fp_line
			(start -0.7874 0.4064)
			(end -0.7874 -0.4064)
			(stroke
				(width 0.1524)
				(type default)
			)
			(layer "F.SilkS")
		)
		(fp_line
			(start 0.7874 0.4064)
			(end -0.7874 0.4064)
			(stroke
				(width 0.1524)
				(type default)
			)
			(layer "F.SilkS")
		)
		(fp_line
			(start -0.7874 -0.4064)
			(end 0.7874 -0.4064)
			(stroke
				(width 0.1524)
				(type default)
			)
			(layer "F.SilkS")
		)
		(fp_line
			(start 0.7874 -0.4064)
			(end 0.7874 0.4064)
			(stroke
				(width 0.1524)
				(type default)
			)
			(layer "F.SilkS")
		)
		(fp_line
			(start -0.67945 0.3048)
			(end -0.67945 -0.305054)
			(stroke
				(width 0.1)
				(type default)
			)
			(layer "F.Fab")
		)
		(fp_line
			(start -0.12065 0.3048)
			(end -0.67945 0.3048)
			(stroke
				(width 0.1)
				(type default)
			)
			(layer "F.Fab")
		)
		(fp_line
			(start 0.120396 0.3048)
			(end 0.120396 0.2794)
			(stroke
				(width 0.1)
				(type default)
			)
			(layer "F.Fab")
		)
		(fp_line
			(start 0.67945 0.3048)
			(end 0.120396 0.3048)
			(stroke
				(width 0.1)
				(type default)
			)
			(layer "F.Fab")
		)
		(fp_line
			(start -0.12065 0.2794)
			(end -0.12065 0.3048)
			(stroke
				(width 0.1)
				(type default)
			)
			(layer "F.Fab")
		)
		(fp_line
			(start 0.120396 0.2794)
			(end -0.12065 0.2794)
			(stroke
				(width 0.1)
				(type default)
			)
			(layer "F.Fab")
		)
		(fp_line
			(start -0.12065 -0.2794)
			(end 0.12065 -0.2794)
			(stroke
				(width 0.1)
				(type default)
			)
			(layer "F.Fab")
		)
		(fp_line
			(start 0.12065 -0.2794)
			(end 0.12065 -0.3048)
			(stroke
				(width 0.1)
				(type default)
			)
			(layer "F.Fab")
		)
		(fp_line
			(start 0.12065 -0.3048)
			(end 0.67945 -0.3048)
			(stroke
				(width 0.1)
				(type default)
			)
			(layer "F.Fab")
		)
		(fp_line
			(start 0.67945 -0.3048)
			(end 0.67945 0.3048)
			(stroke
				(width 0.1)
				(type default)
			)
			(layer "F.Fab")
		)
		(fp_line
			(start -0.67945 -0.305054)
			(end -0.12065 -0.305054)
			(stroke
				(width 0.1)
				(type default)
			)
			(layer "F.Fab")
		)
		(fp_line
			(start -0.12065 -0.305054)
			(end -0.12065 -0.2794)
			(stroke
				(width 0.1)
				(type default)
			)
			(layer "F.Fab")
		)
		(pad "1" smd circle
			(at -0.40005 0 270)
			(size 0 0)
			(layers "F.Cu" "F.Mask" "F.Paste")
			(net "SW_P12V_AUX_PVDDIO_P0_FLT")
		)
		(pad "2" smd circle
			(at 0.40005 0 270)
			(size 0 0)
			(layers "F.Cu" "F.Mask" "F.Paste")
			(net "GND")
		)
	)
)
